# TIMECARD (Time Appliance Project (Time Card)) — schematic netlist excerpt (pin names and nets, part order shuffled) for the footprints in the layout excerpt that follows; sources: Cadence DE-HDL packaged netlist, KiCad conversion of R4006-B0001-02_R01.brd

C231  CAPACITOR  0.01UF 25V 10%  pkg SMC_0201R  page 31 : \1\ = UNNAMED_515_CAPACITOR_I132_1 ; \2\ = SG
CR10  DIODE_2E  pkg SMC_CR_270X232_V1  page 27 : A = SG ; C = XP12R0V_IN

(kicad_pcb
	(version 20260206)
	(generator "pcbnew")
	(generator_version "10.0")
	(general
		(thickness 1.6)
		(legacy_teardrops no)
	)
	(paper "A4")
	(title_block
		(title "timecard-production-celestica-r4006 — R4006-B0001-02_R01.brd")
		(comment 1 "Time Appliance Project (Time Card) / footprints 1-2 of 1113")
	)
	(layers
		(0 "F.Cu" signal "TOP")
		(4 "In1.Cu" signal "L02_GND1")
		(6 "In2.Cu" signal "L03_SIG1")
		(8 "In3.Cu" signal "L04_GND2")
		(10 "In4.Cu" signal "L05_VCC1")
		(12 "In5.Cu" signal "L06_VCC2")
		(14 "In6.Cu" signal "L07_GND3")
		(16 "In7.Cu" signal "L08_SIG2")
		(18 "In8.Cu" signal "L09_GND4")
		(2 "B.Cu" signal "BOTTOM")
		(9 "F.Adhes" user "F.Adhesive")
		(11 "B.Adhes" user "B.Adhesive")
		(13 "F.Paste" user "Package Geometry/Pastemask Top")
		(15 "B.Paste" user "Package Geometry/Pastemask Bottom")
		(5 "F.SilkS" user "Ref Des/Silkscreen Top")
		(7 "B.SilkS" user "Ref Des/Silkscreen Bottom")
		(1 "F.Mask" user "Board Geometry/Soldermask Top")
		(3 "B.Mask" user "Board Geometry/Soldermask Bottom")
		(17 "Dwgs.User" user "User.Drawings")
		(19 "Cmts.User" user "User.Comments")
		(21 "Eco1.User" user "User.Eco1")
		(23 "Eco2.User" user "User.Eco2")
		(25 "Edge.Cuts" user "Board Geometry/Outline")
		(27 "Margin" user)
		(31 "F.CrtYd" user "Package Geometry/Place Bound Top")
		(29 "B.CrtYd" user "Package Geometry/Place Bound Bottom")
		(35 "F.Fab" user "Ref Des/Assembly Top")
		(33 "B.Fab" user "Ref Des/Assembly Bottom")
	)
	(footprint ""
		(layer "F.Cu")
		(at 137.6934 -83.9724)
		(property "Reference" "CR10"
			(at -0.889 -4.65963 0)
			(unlocked yes)
			(layer "F.SilkS")
			(effects
				(font
					(size 0.7874 0.5842)
					(thickness 0.1524)
				)
			)
		)
		(property "Value" "VAL*"
			(at -0.011176 6.627876 0)
			(unlocked yes)
			(layer "F.Fab")
			(hide yes)
			(effects
				(font
					(size 0.7874 0.5842)
					(thickness 0.1524)
				)
			)
		)
		(property "Tolerance" "TOL*"
			(at 0.001524 7.60222 0)
			(unlocked yes)
			(layer "Cmts.User")
			(hide yes)
			(effects
				(font
					(size 0.7874 0.5842)
					(thickness 0.1524)
				)
			)
		)
		(property "User Part Number" "PARTNUM*"
			(at 0 5.66674 0)
			(unlocked yes)
			(layer "Cmts.User")
			(hide yes)
			(effects
				(font
					(size 0.7874 0.5842)
					(thickness 0.1524)
				)
			)
		)
		(property "Device Type" "DIODE_2E-G122-10190-01"
			(at 0 4.47294 0)
			(unlocked yes)
			(layer "F.Fab")
			(hide yes)
			(effects
				(font
					(size 0.7874 0.5842)
					(thickness 0.1524)
				)
			)
		)
		(duplicate_pad_numbers_are_jumpers no)
		(fp_line
			(start -6.311392 -1.896872)
			(end -5.041392 -1.896872)
			(stroke
				(width 0.1)
				(type default)
			)
			(layer "F.SilkS")
		)
		(fp_line
			(start -5.676392 -1.261872)
			(end -5.676392 -2.531872)
			(stroke
				(width 0.1)
				(type default)
			)
			(layer "F.SilkS")
		)
		(fp_line
			(start -4.747768 -3.363976)
			(end 4.747768 -3.363976)
			(stroke
				(width 0.1)
				(type default)
			)
			(layer "F.SilkS")
		)
		(fp_line
			(start -4.747768 3.363976)
			(end -4.747768 -3.363976)
			(stroke
				(width 0.1)
				(type default)
			)
			(layer "F.SilkS")
		)
		(fp_line
			(start 4.747768 -3.363976)
			(end 4.747768 3.363976)
			(stroke
				(width 0.1)
				(type default)
			)
			(layer "F.SilkS")
		)
		(fp_line
			(start 4.747768 3.363976)
			(end -4.747768 3.363976)
			(stroke
				(width 0.1)
				(type default)
			)
			(layer "F.SilkS")
		)
		(fp_rect
			(start -5.001768 -3.617976)
			(end 5.001768 3.617976)
			(stroke
				(width 0)
				(type default)
			)
			(fill no)
			(layer "F.CrtYd")
		)
		(fp_line
			(start -5.295392 -2.024126)
			(end -4.025392 -2.024126)
			(stroke
				(width 0.1)
				(type default)
			)
			(layer "F.Fab")
		)
		(fp_line
			(start -4.660392 -1.389126)
			(end -4.660392 -2.659126)
			(stroke
				(width 0.1)
				(type default)
			)
			(layer "F.Fab")
		)
		(fp_line
			(start -3.554984 -3.109976)
			(end 3.554984 -3.109976)
			(stroke
				(width 0.1)
				(type default)
			)
			(layer "F.Fab")
		)
		(fp_line
			(start -3.554984 3.109976)
			(end -3.554984 -3.109976)
			(stroke
				(width 0.1)
				(type default)
			)
			(layer "F.Fab")
		)
		(fp_line
			(start 3.554984 -3.109976)
			(end 3.554984 3.109976)
			(stroke
				(width 0.1)
				(type default)
			)
			(layer "F.Fab")
		)
		(fp_line
			(start 3.554984 3.109976)
			(end -3.554984 3.109976)
			(stroke
				(width 0.1)
				(type default)
			)
			(layer "F.Fab")
		)
		(fp_text user "A"
			(at -5.7404 -0.18923 0)
			(unlocked yes)
			(layer "F.SilkS")
			(effects
				(font
					(size 0.7874 0.5842)
					(thickness 0.1524)
				)
			)
		)
		(fp_text user "C"
			(at 5.9436 -0.69723 0)
			(unlocked yes)
			(layer "F.SilkS")
			(effects
				(font
					(size 0.7874 0.5842)
					(thickness 0.1524)
				)
			)
		)
		(fp_text user "A"
			(at -4.4704 0.15367 0)
			(unlocked yes)
			(layer "F.Fab")
			(effects
				(font
					(size 0.7874 0.5842)
					(thickness 0.1524)
				)
			)
		)
		(fp_text user "C"
			(at 4.1656 -0.10033 0)
			(unlocked yes)
			(layer "F.Fab")
			(effects
				(font
					(size 0.7874 0.5842)
					(thickness 0.1524)
				)
			)
		)
		(pad "A" smd rect
			(at -3.299968 0)
			(size 2.3876 3.302)
			(layers "F.Cu" "F.Mask" "F.Paste")
			(net "SG")
		)
		(pad "C" smd rect
			(at 3.299968 0)
			(size 2.3876 3.302)
			(layers "F.Cu" "F.Mask" "F.Paste")
			(net "XP12R0V_IN")
		)
	)
	(footprint ""
		(layer "F.Cu")
		(at 146.558 -15.4686)
		(property "Reference" "C231"
			(at 2.667 1.02997 0)
			(unlocked yes)
			(layer "F.SilkS")
			(effects
				(font
					(size 0.7874 0.5842)
					(thickness 0.1524)
				)
			)
		)
		(property "Value" "VAL*"
			(at 0.193548 2.13614 0)
			(unlocked yes)
			(layer "F.Fab")
			(hide yes)
			(effects
				(font
					(size 0.7874 0.5842)
					(thickness 0.1524)
				)
			)
		)
		(property "Tolerance" "TOL*"
			(at 0.216154 3.1496 0)
			(unlocked yes)
			(layer "Cmts.User")
			(hide yes)
			(effects
				(font
					(size 0.7874 0.5842)
					(thickness 0.1524)
				)
			)
		)
		(property "Device Type" "CAPACITOR-G104-0B103-EK,0.01UFA"
			(at 0.184404 1.180592 0)
			(unlocked yes)
			(layer "F.Fab")
			(hide yes)
			(effects
				(font
					(size 0.7874 0.5842)
					(thickness 0.1524)
				)
			)
		)
		(property "User Part Number" "PARTNUM*"
			(at 0.216154 4.185666 0)
			(unlocked yes)
			(layer "Cmts.User")
			(hide yes)
			(effects
				(font
					(size 0.7874 0.5842)
					(thickness 0.1524)
				)
			)
		)
		(duplicate_pad_numbers_are_jumpers no)
		(fp_line
			(start -0.671322 -0.4445)
			(end 0.671322 -0.4445)
			(stroke
				(width 0.1)
				(type default)
			)
			(layer "F.SilkS")
		)
		(fp_line
			(start -0.671322 0.4445)
			(end -0.671322 -0.4445)
			(stroke
				(width 0.1)
				(type default)
			)
			(layer "F.SilkS")
		)
		(fp_line
			(start 0.671322 -0.4445)
			(end 0.671322 0.4445)
			(stroke
				(width 0.1)
				(type default)
			)
			(layer "F.SilkS")
		)
		(fp_line
			(start 0.671322 0.4445)
			(end -0.671322 0.4445)
			(stroke
				(width 0.1)
				(type default)
			)
			(layer "F.SilkS")
		)
		(fp_rect
			(start 0.671322 -0.4445)
			(end -0.671322 0.4445)
			(stroke
				(width 0)
				(type default)
			)
			(fill no)
			(layer "F.CrtYd")
		)
		(fp_line
			(start -0.31496 -0.1651)
			(end -0.31496 0.1651)
			(stroke
				(width 0.1)
				(type default)
			)
			(layer "F.Fab")
		)
		(fp_line
			(start -0.31496 0.1651)
			(end 0.31496 0.1651)
			(stroke
				(width 0.1)
				(type default)
			)
			(layer "F.Fab")
		)
		(fp_line
			(start 0.31496 -0.1651)
			(end -0.31496 -0.1651)
			(stroke
				(width 0.1)
				(type default)
			)
			(layer "F.Fab")
		)
		(fp_line
			(start 0.31496 0.1651)
			(end 0.31496 -0.1651)
			(stroke
				(width 0.1)
				(type default)
			)
			(layer "F.Fab")
		)
		(pad "1" smd rect
			(at -0.264922 0)
			(size 0.3048 0.381)
			(layers "F.Cu" "F.Mask" "F.Paste")
			(net "UNNAMED_515_CAPACITOR_I132_1")
		)
		(pad "2" smd rect
			(at 0.264922 0)
			(size 0.3048 0.381)
			(layers "F.Cu" "F.Mask" "F.Paste")
			(net "SG")
		)
		(zone
			(layer "F.Cu")
			(hatch none 0.5)
			(connect_pads
				(clearance 0)
			)
			(min_thickness 0.25)
			(keepout
				(tracks allowed)
				(vias not_allowed)
				(pads allowed)
				(copperpour not_allowed)
				(footprints allowed)
			)
			(placement
				(enabled no)
				(sheetname "")
			)
			(fill
				(thermal_gap 0.5)
				(thermal_bridge_width 0.5)
				(island_removal_mode 0)
			)
			(polygon
				(pts
					(xy 146.670522 -15.6591) (xy 146.445478 -15.6591) (xy 146.445478 -15.2781) (xy 146.670522 -15.2781)
				)
			)
		)
	)
)
